# T6G (Grand Teton) — schematic netlist excerpt (pin names and nets, part order shuffled) for the footprints in the layout excerpt that follows; sources: Cadence DE-HDL packaged netlist, KiCad conversion of 04192023_DAF0TMB3IC0_F0TG_MB_C_brd_V02_OCP.brd

R1133  Q_RES  1K 1% CHIP  pkg 0402LF  page 136 : A = P3V3_AUX ; B = P12V_OCP_V3_1_PLD_PWRGD

U279  PCA9617ADP  IC  pkg TSSOP8_3XB  page 148
  VCCA  = P3V3_E1S_0
  SCLA  = SMB_E1S_3V3AUX_ISO_SCL_R
  SDAA  = SMB_E1S_3V3AUX_ISO_SDA_R
  GND  = GND
  EN  = SMB_PCIE_E1S_ISO_EN_R
  SDAB  = SMB_SENSOR_E1S_3V3AUX_SDA
  SCLB  = SMB_SENSOR_E1S_3V3AUX_SCL
  VCCB  = P3V3_AUX

(kicad_pcb
	(version 20260206)
	(generator "pcbnew")
	(generator_version "10.0")
	(general
		(thickness 1.6)
		(legacy_teardrops no)
	)
	(paper "A4")
	(title_block
		(title "04192023_DAF0TMB3IC0_F0TG_MB_C_brd_V02_OCP.brd")
		(comment 1 "Grand Teton / footprints 3873-3874 of 8354")
	)
	(layers
		(0 "F.Cu" signal "TOP")
		(4 "In1.Cu" signal "GND")
		(6 "In2.Cu" signal "IN1")
		(8 "In3.Cu" signal "GND1")
		(10 "In4.Cu" signal "IN2")
		(12 "In5.Cu" signal "GND2")
		(14 "In6.Cu" signal "IN3")
		(16 "In7.Cu" signal "GND3")
		(18 "In8.Cu" signal "VCC")
		(20 "In9.Cu" signal "VCC1")
		(22 "In10.Cu" signal "GND4")
		(24 "In11.Cu" signal "IN4")
		(26 "In12.Cu" signal "GND5")
		(28 "In13.Cu" signal "IN5")
		(30 "In14.Cu" signal "GND6")
		(32 "In15.Cu" signal "IN6")
		(34 "In16.Cu" signal "GND7")
		(2 "B.Cu" signal "BOTTOM")
		(9 "F.Adhes" user "F.Adhesive")
		(11 "B.Adhes" user "B.Adhesive")
		(13 "F.Paste" user "Package Geometry/Pastemask Top")
		(15 "B.Paste" user "Package Geometry/Pastemask Bottom")
		(5 "F.SilkS" user "Ref Des/Silkscreen Top")
		(7 "B.SilkS" user "Ref Des/Silkscreen Bottom")
		(1 "F.Mask" user "Board Geometry/Soldermask Top")
		(3 "B.Mask" user "Board Geometry/Soldermask Bottom")
		(17 "Dwgs.User" user "User.Drawings")
		(19 "Cmts.User" user "User.Comments")
		(21 "Eco1.User" user "User.Eco1")
		(23 "Eco2.User" user "User.Eco2")
		(25 "Edge.Cuts" user "Board Geometry/Outline")
		(27 "Margin" user)
		(31 "F.CrtYd" user "Package Geometry/Place Bound Top")
		(29 "B.CrtYd" user "Package Geometry/Place Bound Bottom")
		(35 "F.Fab" user "Ref Des/Assembly Top")
		(33 "B.Fab" user "Ref Des/Assembly Bottom")
	)
	(footprint ""
		(layer "F.Cu")
		(at 204.994764 -96.77908)
		(property "Reference" "R1133"
			(at 0 0 0)
			(layer "F.SilkS")
			(hide yes)
			(effects
				(font
					(size 1.27 1.27)
				)
			)
		)
		(property "Value" ""
			(at 0 0 0)
			(layer "F.Fab")
			(effects
				(font
					(size 1.27 1.27)
				)
			)
		)
		(duplicate_pad_numbers_are_jumpers no)
		(fp_line
			(start -0.7874 -0.4064)
			(end 0.7874 -0.4064)
			(stroke
				(width 0.1524)
				(type default)
			)
			(layer "F.SilkS")
		)
		(fp_line
			(start -0.7874 0.4064)
			(end -0.7874 -0.4064)
			(stroke
				(width 0.1524)
				(type default)
			)
			(layer "F.SilkS")
		)
		(fp_line
			(start 0.7874 -0.4064)
			(end 0.7874 0.4064)
			(stroke
				(width 0.1524)
				(type default)
			)
			(layer "F.SilkS")
		)
		(fp_line
			(start 0.7874 0.4064)
			(end -0.7874 0.4064)
			(stroke
				(width 0.1524)
				(type default)
			)
			(layer "F.SilkS")
		)
		(fp_line
			(start -0.67945 -0.305054)
			(end -0.12065 -0.305054)
			(stroke
				(width 0.1)
				(type default)
			)
			(layer "F.Fab")
		)
		(fp_line
			(start -0.67945 0.3048)
			(end -0.67945 -0.305054)
			(stroke
				(width 0.1)
				(type default)
			)
			(layer "F.Fab")
		)
		(fp_line
			(start -0.12065 -0.305054)
			(end -0.12065 -0.2794)
			(stroke
				(width 0.1)
				(type default)
			)
			(layer "F.Fab")
		)
		(fp_line
			(start -0.12065 -0.2794)
			(end 0.12065 -0.2794)
			(stroke
				(width 0.1)
				(type default)
			)
			(layer "F.Fab")
		)
		(fp_line
			(start -0.12065 0.2794)
			(end -0.12065 0.3048)
			(stroke
				(width 0.1)
				(type default)
			)
			(layer "F.Fab")
		)
		(fp_line
			(start -0.12065 0.3048)
			(end -0.67945 0.3048)
			(stroke
				(width 0.1)
				(type default)
			)
			(layer "F.Fab")
		)
		(fp_line
			(start 0.120396 0.2794)
			(end -0.12065 0.2794)
			(stroke
				(width 0.1)
				(type default)
			)
			(layer "F.Fab")
		)
		(fp_line
			(start 0.120396 0.3048)
			(end 0.120396 0.2794)
			(stroke
				(width 0.1)
				(type default)
			)
			(layer "F.Fab")
		)
		(fp_line
			(start 0.12065 -0.3048)
			(end 0.67945 -0.3048)
			(stroke
				(width 0.1)
				(type default)
			)
			(layer "F.Fab")
		)
		(fp_line
			(start 0.12065 -0.2794)
			(end 0.12065 -0.3048)
			(stroke
				(width 0.1)
				(type default)
			)
			(layer "F.Fab")
		)
		(fp_line
			(start 0.67945 -0.3048)
			(end 0.67945 0.3048)
			(stroke
				(width 0.1)
				(type default)
			)
			(layer "F.Fab")
		)
		(fp_line
			(start 0.67945 0.3048)
			(end 0.120396 0.3048)
			(stroke
				(width 0.1)
				(type default)
			)
			(layer "F.Fab")
		)
		(pad "1" smd circle
			(at -0.40005 0)
			(size 0 0)
			(layers "F.Cu" "F.Mask" "F.Paste")
			(net "P3V3_AUX")
		)
		(pad "2" smd circle
			(at 0.40005 0)
			(size 0 0)
			(layers "F.Cu" "F.Mask" "F.Paste")
			(net "P12V_OCP_V3_1_PLD_PWRGD")
		)
	)
	(footprint ""
		(layer "F.Cu")
		(at 216.18575 -43.738292 180)
		(property "Reference" "U279"
			(at 0.6731 2.330704 0)
			(unlocked yes)
			(layer "F.SilkS")
			(effects
				(font
					(size 0.7874 0.5842)
					(thickness 0.1524)
				)
				(justify left)
			)
		)
		(property "Value" ""
			(at 0 0 180)
			(layer "F.Fab")
			(effects
				(font
					(size 1.27 1.27)
				)
			)
		)
		(duplicate_pad_numbers_are_jumpers no)
		(fp_line
			(start 1.463548 1.549908)
			(end -1.463548 1.549908)
			(stroke
				(width 0.1524)
				(type default)
			)
			(layer "F.SilkS")
		)
		(fp_line
			(start 1.463548 -1.549908)
			(end 1.463548 1.549908)
			(stroke
				(width 0.1524)
				(type default)
			)
			(layer "F.SilkS")
		)
		(fp_line
			(start 0.762 -1.549908)
			(end 1.463548 -1.549908)
			(stroke
				(width 0.1524)
				(type default)
			)
			(layer "F.SilkS")
		)
		(fp_line
			(start 0 -0.762)
			(end 0.762 -1.549908)
			(stroke
				(width 0.1524)
				(type default)
			)
			(layer "F.SilkS")
		)
		(fp_line
			(start -0.787908 -1.549908)
			(end 0 -0.762)
			(stroke
				(width 0.1524)
				(type default)
			)
			(layer "F.SilkS")
		)
		(fp_line
			(start -1.463548 1.549908)
			(end -1.463548 -1.549908)
			(stroke
				(width 0.1524)
				(type default)
			)
			(layer "F.SilkS")
		)
		(fp_line
			(start -1.463548 -1.549908)
			(end -0.787908 -1.549908)
			(stroke
				(width 0.1524)
				(type default)
			)
			(layer "F.SilkS")
		)
		(fp_poly
			(pts
				(xy -2.453386 -2.164842) (xy -1.833626 -2.164842) (xy -2.143506 -1.545082)
			)
			(stroke
				(width 0)
				(type default)
			)
			(fill yes)
			(layer "F.SilkS")
		)
		(fp_line
			(start 1.549908 1.549908)
			(end -1.549908 1.549908)
			(stroke
				(width 0.1)
				(type default)
			)
			(layer "F.Fab")
		)
		(fp_line
			(start 1.549908 -1.549908)
			(end 1.549908 1.549908)
			(stroke
				(width 0.1)
				(type default)
			)
			(layer "F.Fab")
		)
		(fp_line
			(start -1.549908 1.549908)
			(end -1.549908 -1.549908)
			(stroke
				(width 0.1)
				(type default)
			)
			(layer "F.Fab")
		)
		(fp_line
			(start -1.549908 -1.549908)
			(end 1.549908 -1.549908)
			(stroke
				(width 0.1)
				(type default)
			)
			(layer "F.Fab")
		)
		(fp_poly
			(pts
				(xy -3.4798 -1.359916) (xy -2.86004 -1.050036) (xy -3.4798 -0.740156)
			)
			(stroke
				(width 0)
				(type default)
			)
			(fill yes)
			(layer "F.Fab")
		)
		(pad "1" smd rect
			(at -2.175002 -1.050036 270)
			(size 0.6096 1.1684)
			(layers "F.Cu" "F.Mask" "F.Paste")
			(net "P3V3_E1S_0")
		)
		(pad "2" smd rect
			(at -2.175002 -0.32512 270)
			(size 0.4318 1.1684)
			(layers "F.Cu" "F.Mask" "F.Paste")
			(net "SMB_E1S_3V3AUX_ISO_SCL_R")
		)
		(pad "3" smd rect
			(at -2.175002 0.32512 270)
			(size 0.4318 1.1684)
			(layers "F.Cu" "F.Mask" "F.Paste")
			(net "SMB_E1S_3V3AUX_ISO_SDA_R")
		)
		(pad "4" smd rect
			(at -2.175002 1.050036 270)
			(size 0.6096 1.1684)
			(layers "F.Cu" "F.Mask" "F.Paste")
			(net "GND")
		)
		(pad "5" smd rect
			(at 2.175002 1.050036 270)
			(size 0.6096 1.1684)
			(layers "F.Cu" "F.Mask" "F.Paste")
			(net "SMB_PCIE_E1S_ISO_EN_R")
		)
		(pad "6" smd rect
			(at 2.175002 0.32512 270)
			(size 0.4318 1.1684)
			(layers "F.Cu" "F.Mask" "F.Paste")
			(net "SMB_SENSOR_E1S_3V3AUX_SDA")
		)
		(pad "7" smd rect
			(at 2.175002 -0.32512 270)
			(size 0.4318 1.1684)
			(layers "F.Cu" "F.Mask" "F.Paste")
			(net "SMB_SENSOR_E1S_3V3AUX_SCL")
		)
		(pad "8" smd rect
			(at 2.175002 -1.050036 270)
			(size 0.6096 1.1684)
			(layers "F.Cu" "F.Mask" "F.Paste")
			(net "P3V3_AUX")
		)
	)
)
